# S9S_MB_2U (Grand Teton) — schematic netlist excerpt (pin names and nets, part order shuffled) for the footprints in the layout excerpt that follows; sources: Cadence DE-HDL packaged netlist, KiCad conversion of 03242023_DA0F0TMBIJ0_F0T_Motherboard_J_brd_V01_OCP.brd

PC541_P1_4  Q_CAP  22UF 4V 20% X6S  pkg C0805  page 286 : A = PVCCIN_CPU1 ; B = GND
R158  Q_RES  100 1% CHIP  pkg 0402LF  page 125 : A = RST_CPU1_BUF_R_N ; B = RST_CPU1_LVC1_N
PC1187  Q_CAPP  330UF 2.5V +10/-35% SPCAP  pkg SMLF  page 272 : A = PVCCFA_EHV_FIVRA_CPU0 ; B = GND

(kicad_pcb
	(version 20260206)
	(generator "pcbnew")
	(generator_version "10.0")
	(general
		(thickness 1.6)
		(legacy_teardrops no)
	)
	(paper "A4")
	(title_block
		(title "03242023_DA0F0TMBIJ0_F0T_Motherboard_J_brd_V01_OCP.brd")
		(comment 1 "Grand Teton / footprints 4305-4307 of 6105")
	)
	(layers
		(0 "F.Cu" signal "TOP")
		(4 "In1.Cu" signal "GND")
		(6 "In2.Cu" signal "IN1")
		(8 "In3.Cu" signal "GND1")
		(10 "In4.Cu" signal "IN2")
		(12 "In5.Cu" signal "GND2")
		(14 "In6.Cu" signal "IN3")
		(16 "In7.Cu" signal "GND3")
		(18 "In8.Cu" signal "VCC")
		(20 "In9.Cu" signal "VCC1")
		(22 "In10.Cu" signal "GND4")
		(24 "In11.Cu" signal "IN4")
		(26 "In12.Cu" signal "GND5")
		(28 "In13.Cu" signal "IN5")
		(30 "In14.Cu" signal "GND6")
		(32 "In15.Cu" signal "IN6")
		(34 "In16.Cu" signal "GND7")
		(2 "B.Cu" signal "BOTTOM")
		(9 "F.Adhes" user "F.Adhesive")
		(11 "B.Adhes" user "B.Adhesive")
		(13 "F.Paste" user "Package Geometry/Pastemask Top")
		(15 "B.Paste" user "Package Geometry/Pastemask Bottom")
		(5 "F.SilkS" user "Ref Des/Silkscreen Top")
		(7 "B.SilkS" user "Ref Des/Silkscreen Bottom")
		(1 "F.Mask" user "Board Geometry/Soldermask Top")
		(3 "B.Mask" user "Board Geometry/Soldermask Bottom")
		(17 "Dwgs.User" user "User.Drawings")
		(19 "Cmts.User" user "User.Comments")
		(21 "Eco1.User" user "User.Eco1")
		(23 "Eco2.User" user "User.Eco2")
		(25 "Edge.Cuts" user "Board Geometry/Outline")
		(27 "Margin" user)
		(31 "F.CrtYd" user "Package Geometry/Place Bound Top")
		(29 "B.CrtYd" user "Package Geometry/Place Bound Bottom")
		(35 "F.Fab" user "Ref Des/Assembly Top")
		(33 "B.Fab" user "Ref Des/Assembly Bottom")
	)
	(footprint ""
		(layer "B.Cu")
		(at 426.00118 -354.903786 -90)
		(property "Reference" "PC1187"
			(at 0 0 90)
			(layer "B.SilkS")
			(hide yes)
			(effects
				(font
					(size 1.27 1.27)
				)
				(justify mirror)
			)
		)
		(property "Value" ""
			(at 0 0 90)
			(layer "B.Fab")
			(effects
				(font
					(size 1.27 1.27)
				)
				(justify mirror)
			)
		)
		(duplicate_pad_numbers_are_jumpers no)
		(fp_line
			(start -4.533392 2.249932)
			(end 4.533392 2.249932)
			(stroke
				(width 0.1524)
				(type default)
			)
			(layer "B.SilkS")
		)
		(fp_line
			(start 4.533392 2.249932)
			(end 4.533392 -2.249932)
			(stroke
				(width 0.1524)
				(type default)
			)
			(layer "B.SilkS")
		)
		(fp_line
			(start -4.533392 -2.249932)
			(end -4.533392 2.249932)
			(stroke
				(width 0.1524)
				(type default)
			)
			(layer "B.SilkS")
		)
		(fp_line
			(start 4.533392 -2.249932)
			(end -4.533392 -2.249932)
			(stroke
				(width 0.1524)
				(type default)
			)
			(layer "B.SilkS")
		)
		(fp_rect
			(start 5.39242 2.326132)
			(end 4.533392 -2.326132)
			(stroke
				(width 0)
				(type default)
			)
			(fill yes)
			(layer "B.SilkS")
		)
		(fp_line
			(start -3.750056 2.249932)
			(end 3.750056 2.249932)
			(stroke
				(width 0.1)
				(type default)
			)
			(layer "B.Fab")
		)
		(fp_line
			(start 3.750056 2.249932)
			(end 3.750056 -2.249932)
			(stroke
				(width 0.1)
				(type default)
			)
			(layer "B.Fab")
		)
		(fp_line
			(start -3.750056 -2.249932)
			(end -3.750056 2.249932)
			(stroke
				(width 0.1)
				(type default)
			)
			(layer "B.Fab")
		)
		(fp_line
			(start 3.750056 -2.249932)
			(end -3.750056 -2.249932)
			(stroke
				(width 0.1)
				(type default)
			)
			(layer "B.Fab")
		)
		(fp_text user "-"
			(at -4.659122 1.76911 270)
			(unlocked yes)
			(layer "B.SilkS")
			(effects
				(font
					(size 1.905 1.4224)
					(thickness 0.1524)
				)
				(justify left mirror)
			)
		)
		(fp_text user "+"
			(at 6.322314 0.786384 180)
			(unlocked yes)
			(layer "B.SilkS")
			(effects
				(font
					(size 1.905 1.4224)
					(thickness 0.1524)
				)
				(justify left mirror)
			)
		)
		(fp_text user "+"
			(at 6.322314 0.786384 180)
			(unlocked yes)
			(layer "B.Fab")
			(effects
				(font
					(size 1.905 1.4224)
					(thickness 0.1524)
				)
				(justify left mirror)
			)
		)
		(fp_text user "-"
			(at -4.8514 -0.14605 270)
			(unlocked yes)
			(layer "B.Fab")
			(effects
				(font
					(size 1.905 1.4224)
					(thickness 0.1524)
				)
				(justify left mirror)
			)
		)
		(pad "1" smd rect
			(at 3.199892 0 90)
			(size 2.413 2.8194)
			(layers "B.Cu" "B.Mask" "B.Paste")
			(net "PVCCFA_EHV_FIVRA_CPU0")
		)
		(pad "2" smd rect
			(at -3.199892 0 90)
			(size 2.413 2.8194)
			(layers "B.Cu" "B.Mask" "B.Paste")
			(net "GND")
		)
	)
	(footprint ""
		(layer "B.Cu")
		(at 66.107564 -243.345462 180)
		(property "Reference" "R158"
			(at 0 0 0)
			(layer "B.SilkS")
			(hide yes)
			(effects
				(font
					(size 1.27 1.27)
				)
				(justify mirror)
			)
		)
		(property "Value" ""
			(at 0 0 0)
			(layer "B.Fab")
			(effects
				(font
					(size 1.27 1.27)
				)
				(justify mirror)
			)
		)
		(duplicate_pad_numbers_are_jumpers no)
		(fp_line
			(start 0.7874 0.4064)
			(end 0.7874 -0.4064)
			(stroke
				(width 0.1524)
				(type default)
			)
			(layer "B.SilkS")
		)
		(fp_line
			(start 0.7874 -0.4064)
			(end -0.7874 -0.4064)
			(stroke
				(width 0.1524)
				(type default)
			)
			(layer "B.SilkS")
		)
		(fp_line
			(start -0.7874 0.4064)
			(end 0.7874 0.4064)
			(stroke
				(width 0.1524)
				(type default)
			)
			(layer "B.SilkS")
		)
		(fp_line
			(start -0.7874 -0.4064)
			(end -0.7874 0.4064)
			(stroke
				(width 0.1524)
				(type default)
			)
			(layer "B.SilkS")
		)
		(fp_line
			(start 0.67945 0.3048)
			(end 0.67945 -0.305054)
			(stroke
				(width 0.1)
				(type default)
			)
			(layer "B.Fab")
		)
		(fp_line
			(start 0.67945 -0.305054)
			(end 0.12065 -0.305054)
			(stroke
				(width 0.1)
				(type default)
			)
			(layer "B.Fab")
		)
		(fp_line
			(start 0.12065 0.3048)
			(end 0.67945 0.3048)
			(stroke
				(width 0.1)
				(type default)
			)
			(layer "B.Fab")
		)
		(fp_line
			(start 0.12065 0.2794)
			(end 0.12065 0.3048)
			(stroke
				(width 0.1)
				(type default)
			)
			(layer "B.Fab")
		)
		(fp_line
			(start 0.12065 -0.2794)
			(end -0.12065 -0.2794)
			(stroke
				(width 0.1)
				(type default)
			)
			(layer "B.Fab")
		)
		(fp_line
			(start 0.12065 -0.305054)
			(end 0.12065 -0.2794)
			(stroke
				(width 0.1)
				(type default)
			)
			(layer "B.Fab")
		)
		(fp_line
			(start -0.120396 0.3048)
			(end -0.120396 0.2794)
			(stroke
				(width 0.1)
				(type default)
			)
			(layer "B.Fab")
		)
		(fp_line
			(start -0.120396 0.2794)
			(end 0.12065 0.2794)
			(stroke
				(width 0.1)
				(type default)
			)
			(layer "B.Fab")
		)
		(fp_line
			(start -0.12065 -0.2794)
			(end -0.12065 -0.3048)
			(stroke
				(width 0.1)
				(type default)
			)
			(layer "B.Fab")
		)
		(fp_line
			(start -0.12065 -0.3048)
			(end -0.67945 -0.3048)
			(stroke
				(width 0.1)
				(type default)
			)
			(layer "B.Fab")
		)
		(fp_line
			(start -0.67945 0.3048)
			(end -0.120396 0.3048)
			(stroke
				(width 0.1)
				(type default)
			)
			(layer "B.Fab")
		)
		(fp_line
			(start -0.67945 -0.3048)
			(end -0.67945 0.3048)
			(stroke
				(width 0.1)
				(type default)
			)
			(layer "B.Fab")
		)
		(pad "1" smd circle
			(at 0.40005 0)
			(size 0 0)
			(layers "B.Cu" "B.Mask" "B.Paste")
			(net "RST_CPU1_BUF_R_N")
		)
		(pad "2" smd circle
			(at -0.40005 0)
			(size 0 0)
			(layers "B.Cu" "B.Mask" "B.Paste")
			(net "RST_CPU1_LVC1_N")
		)
	)
	(footprint ""
		(layer "B.Cu")
		(at 120.858534 -324.792086 -90)
		(property "Reference" "PC541_P1_4"
			(at 0 0 90)
			(layer "B.SilkS")
			(hide yes)
			(effects
				(font
					(size 1.27 1.27)
				)
				(justify mirror)
			)
		)
		(property "Value" ""
			(at 0 0 90)
			(layer "B.Fab")
			(effects
				(font
					(size 1.27 1.27)
				)
				(justify mirror)
			)
		)
		(duplicate_pad_numbers_are_jumpers no)
		(fp_line
			(start -1.524 0.762)
			(end 1.524 0.762)
			(stroke
				(width 0.1524)
				(type default)
			)
			(layer "B.SilkS")
		)
		(fp_line
			(start 1.524 0.762)
			(end 1.524 -0.762)
			(stroke
				(width 0.1524)
				(type default)
			)
			(layer "B.SilkS")
		)
		(fp_line
			(start -1.524 -0.762)
			(end -1.524 0.762)
			(stroke
				(width 0.1524)
				(type default)
			)
			(layer "B.SilkS")
		)
		(fp_line
			(start 1.524 -0.762)
			(end -1.524 -0.762)
			(stroke
				(width 0.1524)
				(type default)
			)
			(layer "B.SilkS")
		)
		(fp_line
			(start -1.1049 0.724916)
			(end -1.1049 -0.724916)
			(stroke
				(width 0.1)
				(type default)
			)
			(layer "B.Fab")
		)
		(fp_line
			(start 1.1049 0.724916)
			(end -1.1049 0.724916)
			(stroke
				(width 0.1)
				(type default)
			)
			(layer "B.Fab")
		)
		(fp_line
			(start -1.1049 -0.724916)
			(end 1.1049 -0.724916)
			(stroke
				(width 0.1)
				(type default)
			)
			(layer "B.Fab")
		)
		(fp_line
			(start 1.1049 -0.724916)
			(end 1.1049 0.724916)
			(stroke
				(width 0.1)
				(type default)
			)
			(layer "B.Fab")
		)
		(pad "1" smd rect
			(at 0.889 0 270)
			(size 1.016 1.27)
			(layers "B.Cu" "B.Mask" "B.Paste")
			(net "PVCCIN_CPU1")
		)
		(pad "2" smd rect
			(at -0.889 0 270)
			(size 1.016 1.27)
			(layers "B.Cu" "B.Mask" "B.Paste")
			(net "GND")
		)
	)
)
